(kicad_pcb
	(version 20241229)
	(generator "pcbnew")
	(generator_version "9.0")
	(general
		(thickness 1.292)
		(legacy_teardrops no)
	)
	(paper "A4")
	(title_block
		(title "LPDDR5 Testbed")
		(date "2023-12-19")
		(rev "1.0.0")
		(comment 9 "footprints 44-49 of 160")
	)
	(layers
		(0 "F.Cu" signal)
		(4 "In1.Cu" power)
		(6 "In2.Cu" power)
		(8 "In3.Cu" signal)
		(10 "In4.Cu" signal)
		(2 "B.Cu" signal)
		(9 "F.Adhes" user "F.Adhesive")
		(11 "B.Adhes" user "B.Adhesive")
		(13 "F.Paste" user)
		(15 "B.Paste" user)
		(5 "F.SilkS" user "F.Silkscreen")
		(7 "B.SilkS" user "B.Silkscreen")
		(1 "F.Mask" user)
		(3 "B.Mask" user)
		(17 "Dwgs.User" user "User.Drawings")
		(19 "Cmts.User" user "User.Comments")
		(21 "Eco1.User" user "User.Eco1")
		(23 "Eco2.User" user "User.Eco2")
		(25 "Edge.Cuts" user)
		(27 "Margin" user)
		(31 "F.CrtYd" user "F.Courtyard")
		(29 "B.CrtYd" user "B.Courtyard")
		(35 "F.Fab" user)
		(33 "B.Fab" user)
	)
	(footprint "antmicro-footprints:TP_SMD_1mm"
		(layer "F.Cu")
		(at 119.25 65.4 90)
		(property "Reference" "TP2"
			(at 0.6 0.35 90)
			(unlocked yes)
			(layer "F.SilkS")
			(effects
				(font
					(size 0.7 0.7)
					(thickness 0.15)
				)
				(justify left bottom)
			)
		)
		(property "Value" "TP_1mm_SMD"
			(at 0 1.4 90)
			(layer "F.Fab")
			(effects
				(font
					(size 0.7 0.7)
					(thickness 0.15)
				)
				(justify left bottom)
			)
		)
		(property "Author" "Antmicro"
			(at 184.65 -53.85 0)
			(layer "F.Fab")
			(hide yes)
			(effects
				(font
					(size 1 1)
					(thickness 0.15)
				)
			)
		)
		(property "License" "Apache-2.0"
			(at 184.65 -53.85 0)
			(layer "F.Fab")
			(hide yes)
			(effects
				(font
					(size 1 1)
					(thickness 0.15)
				)
			)
		)
		(property "MPN" ""
			(at 184.65 -53.85 0)
			(layer "F.Fab")
			(hide yes)
			(effects
				(font
					(size 1 1)
					(thickness 0.15)
				)
			)
		)
		(property "Manufacturer" ""
			(at 184.65 -53.85 0)
			(layer "F.Fab")
			(hide yes)
			(effects
				(font
					(size 1 1)
					(thickness 0.15)
				)
			)
		)
		(sheetname "Power supply")
		(sheetfile "power_supply.kicad_sch")
		(attr exclude_from_pos_files)
		(pad "1" smd circle
			(at 0 0 90)
			(size 1 1)
			(layers "F.Cu" "F.Mask")
			(net 38 "/Power supply/I2C.SDA")
			(pinfunction "1")
			(pintype "passive")
		)
	)
	(footprint "antmicro-footprints:R_0402_1005Metric"
		(layer "F.Cu")
		(at 110.0025 72.755)
		(descr "Resistor SMD 0402")
		(tags "resistor SMD 0402")
		(property "Reference" "R37"
			(at 0.8975 0.445 0)
			(unlocked yes)
			(layer "F.SilkS")
			(effects
				(font
					(size 0.7 0.7)
					(thickness 0.15)
				)
				(justify left bottom)
			)
		)
		(property "Value" "R_100k_0402"
			(at -1.011843 1.772047 0)
			(layer "F.Fab")
			(effects
				(font
					(size 0.7 0.7)
					(thickness 0.15)
				)
				(justify left bottom)
			)
		)
		(property "Author" "Antmicro"
			(at 0 0 0)
			(layer "F.Fab")
			(hide yes)
			(effects
				(font
					(size 1 1)
					(thickness 0.15)
				)
			)
		)
		(property "License" "Apache-2.0"
			(at 0 0 0)
			(layer "F.Fab")
			(hide yes)
			(effects
				(font
					(size 1 1)
					(thickness 0.15)
				)
			)
		)
		(property "MPN" "CR0402-FX-1003GLF"
			(at 0 0 0)
			(layer "F.Fab")
			(hide yes)
			(effects
				(font
					(size 1 1)
					(thickness 0.15)
				)
			)
		)
		(property "Manufacturer" "Bourns"
			(at 0 0 0)
			(layer "F.Fab")
			(hide yes)
			(effects
				(font
					(size 1 1)
					(thickness 0.15)
				)
			)
		)
		(property "Tolerance" "1%"
			(at 0 0 0)
			(layer "F.Fab")
			(hide yes)
			(effects
				(font
					(size 1 1)
					(thickness 0.15)
				)
			)
		)
		(property "Val" "100k"
			(at 0 0 0)
			(layer "F.Fab")
			(hide yes)
			(effects
				(font
					(size 1 1)
					(thickness 0.15)
				)
			)
		)
		(sheetname "Power supply")
		(sheetfile "power_supply.kicad_sch")
		(attr smd)
		(fp_rect
			(start -0.93 -0.47)
			(end 0.93 0.47)
			(stroke
				(width 0.05)
				(type solid)
			)
			(fill no)
			(layer "F.CrtYd")
		)
		(fp_rect
			(start -0.5 -0.25)
			(end 0.5 0.25)
			(stroke
				(width 0.15)
				(type solid)
			)
			(fill no)
			(layer "F.Fab")
		)
		(pad "1" smd roundrect
			(at -0.485 0)
			(size 0.59 0.64)
			(layers "F.Cu" "F.Mask" "F.Paste")
			(roundrect_rratio 0.25)
			(net 72 "/Power supply/FB3")
			(pintype "passive")
		)
		(pad "2" smd roundrect
			(at 0.485 0)
			(size 0.59 0.64)
			(layers "F.Cu" "F.Mask" "F.Paste")
			(roundrect_rratio 0.25)
			(net 9 "/Power supply/VOUT3")
			(pintype "passive")
		)
	)
	(footprint "antmicro-footprints:R_Array_4x0402_Panasonic_EXB28V"
		(layer "F.Cu")
		(at 162.7125 93.8)
		(property "Reference" "R58"
			(at -1.301 -1.45 0)
			(unlocked yes)
			(layer "F.SilkS")
			(effects
				(font
					(size 0.7 0.7)
					(thickness 0.15)
				)
				(justify left bottom)
			)
		)
		(property "Value" "R_4x100R_0402_array"
			(at -1.5 2 0)
			(layer "F.Fab")
			(effects
				(font
					(size 0.7 0.7)
					(thickness 0.15)
				)
				(justify left bottom)
			)
		)
		(property "Author" "Antmicro"
			(at 0 0 0)
			(layer "F.Fab")
			(hide yes)
			(effects
				(font
					(size 1 1)
					(thickness 0.15)
				)
			)
		)
		(property "License" "Apache-2.0"
			(at 0 0 0)
			(layer "F.Fab")
			(hide yes)
			(effects
				(font
					(size 1 1)
					(thickness 0.15)
				)
			)
		)
		(property "MPN" "EXB-28V101JX"
			(at 0 0 0)
			(layer "F.Fab")
			(hide yes)
			(effects
				(font
					(size 1 1)
					(thickness 0.15)
				)
			)
		)
		(property "Manufacturer" "Panasonic"
			(at 0 0 0)
			(layer "F.Fab")
			(hide yes)
			(effects
				(font
					(size 1 1)
					(thickness 0.15)
				)
			)
		)
		(property "Val" "R_4x100R_0402"
			(at 0 0 0)
			(layer "F.Fab")
			(hide yes)
			(effects
				(font
					(size 1 1)
					(thickness 0.15)
				)
			)
		)
		(sheetname "Translators1")
		(sheetfile "translators.kicad_sch")
		(attr smd)
		(fp_line
			(start -1.25 -0.5)
			(end -1.25 0.498)
			(stroke
				(width 0.15)
				(type solid)
			)
			(layer "F.SilkS")
		)
		(fp_line
			(start 1.25 0.499)
			(end 1.25 -0.499)
			(stroke
				(width 0.15)
				(type solid)
			)
			(layer "F.SilkS")
		)
		(fp_rect
			(start -1.25 -0.8)
			(end 1.25 0.8)
			(stroke
				(width 0.05)
				(type solid)
			)
			(fill no)
			(layer "F.CrtYd")
		)
		(fp_line
			(start -1 -0.5)
			(end 0.998 -0.5)
			(stroke
				(width 0.15)
				(type solid)
			)
			(layer "F.Fab")
		)
		(fp_line
			(start -1 0.498)
			(end -1 -0.5)
			(stroke
				(width 0.15)
				(type solid)
			)
			(layer "F.Fab")
		)
		(fp_line
			(start 0.998 -0.5)
			(end 0.998 0.498)
			(stroke
				(width 0.15)
				(type solid)
			)
			(layer "F.Fab")
		)
		(fp_line
			(start 0.998 0.498)
			(end -1 0.498)
			(stroke
				(width 0.15)
				(type solid)
			)
			(layer "F.Fab")
		)
		(pad "1" smd roundrect
			(at -0.8875 0.45)
			(size 0.525 0.5)
			(layers "F.Cu" "F.Mask" "F.Paste")
			(roundrect_rratio 0.25)
			(net 130 "/SODIMM/LPDDR5_IN_B.DQ5")
			(pinfunction "R1.1")
			(pintype "passive")
		)
		(pad "2" smd roundrect
			(at -0.25 0.45)
			(size 0.25 0.5)
			(layers "F.Cu" "F.Mask" "F.Paste")
			(roundrect_rratio 0.25)
			(net 129 "/SODIMM/LPDDR5_IN_B.DQ4")
			(pinfunction "R2.1")
			(pintype "passive")
		)
		(pad "3" smd roundrect
			(at 0.25 0.45)
			(size 0.25 0.5)
			(layers "F.Cu" "F.Mask" "F.Paste")
			(roundrect_rratio 0.25)
			(net 131 "/SODIMM/LPDDR5_IN_B.DQ6")
			(pinfunction "R3.1")
			(pintype "passive")
		)
		(pad "4" smd roundrect
			(at 0.8875 0.45)
			(size 0.525 0.5)
			(layers "F.Cu" "F.Mask" "F.Paste")
			(roundrect_rratio 0.25)
			(net 132 "/SODIMM/LPDDR5_IN_B.DQ7")
			(pinfunction "R4.1")
			(pintype "passive")
		)
		(pad "5" smd roundrect
			(at 0.8875 -0.45)
			(size 0.525 0.5)
			(layers "F.Cu" "F.Mask" "F.Paste")
			(roundrect_rratio 0.25)
			(net 217 "/LPDDR5/LPDDR5_B.DQ7")
			(pinfunction "R4.2")
			(pintype "passive")
		)
		(pad "6" smd roundrect
			(at 0.25 -0.45)
			(size 0.25 0.5)
			(layers "F.Cu" "F.Mask" "F.Paste")
			(roundrect_rratio 0.25)
			(net 218 "/LPDDR5/LPDDR5_B.DQ6")
			(pinfunction "R3.2")
			(pintype "passive")
		)
		(pad "7" smd roundrect
			(at -0.25 -0.45)
			(size 0.25 0.5)
			(layers "F.Cu" "F.Mask" "F.Paste")
			(roundrect_rratio 0.25)
			(net 220 "/LPDDR5/LPDDR5_B.DQ4")
			(pinfunction "R2.2")
			(pintype "passive")
		)
		(pad "8" smd roundrect
			(at -0.8875 -0.45)
			(size 0.525 0.5)
			(layers "F.Cu" "F.Mask" "F.Paste")
			(roundrect_rratio 0.25)
			(net 219 "/LPDDR5/LPDDR5_B.DQ5")
			(pinfunction "R1.2")
			(pintype "passive")
		)
	)
	(footprint "antmicro-footprints:R_Array_4x0402_Panasonic_EXB28V"
		(layer "F.Cu")
		(at 152.2 93.8)
		(property "Reference" "R62"
			(at -1.301 -1.45 0)
			(unlocked yes)
			(layer "F.SilkS")
			(effects
				(font
					(size 0.7 0.7)
					(thickness 0.15)
				)
				(justify left bottom)
			)
		)
		(property "Value" "R_4x100R_0402_array"
			(at -1.5 2 0)
			(layer "F.Fab")
			(effects
				(font
					(size 0.7 0.7)
					(thickness 0.15)
				)
				(justify left bottom)
			)
		)
		(property "Author" "Antmicro"
			(at 0 0 0)
			(layer "F.Fab")
			(hide yes)
			(effects
				(font
					(size 1 1)
					(thickness 0.15)
				)
			)
		)
		(property "License" "Apache-2.0"
			(at 0 0 0)
			(layer "F.Fab")
			(hide yes)
			(effects
				(font
					(size 1 1)
					(thickness 0.15)
				)
			)
		)
		(property "MPN" "EXB-28V101JX"
			(at 0 0 0)
			(layer "F.Fab")
			(hide yes)
			(effects
				(font
					(size 1 1)
					(thickness 0.15)
				)
			)
		)
		(property "Manufacturer" "Panasonic"
			(at 0 0 0)
			(layer "F.Fab")
			(hide yes)
			(effects
				(font
					(size 1 1)
					(thickness 0.15)
				)
			)
		)
		(property "Val" "R_4x100R_0402"
			(at 0 0 0)
			(layer "F.Fab")
			(hide yes)
			(effects
				(font
					(size 1 1)
					(thickness 0.15)
				)
			)
		)
		(sheetname "Translators1")
		(sheetfile "translators.kicad_sch")
		(attr smd)
		(fp_line
			(start -1.25 -0.5)
			(end -1.25 0.498)
			(stroke
				(width 0.15)
				(type solid)
			)
			(layer "F.SilkS")
		)
		(fp_line
			(start 1.25 0.499)
			(end 1.25 -0.499)
			(stroke
				(width 0.15)
				(type solid)
			)
			(layer "F.SilkS")
		)
		(fp_rect
			(start -1.25 -0.8)
			(end 1.25 0.8)
			(stroke
				(width 0.05)
				(type solid)
			)
			(fill no)
			(layer "F.CrtYd")
		)
		(fp_line
			(start -1 -0.5)
			(end 0.998 -0.5)
			(stroke
				(width 0.15)
				(type solid)
			)
			(layer "F.Fab")
		)
		(fp_line
			(start -1 0.498)
			(end -1 -0.5)
			(stroke
				(width 0.15)
				(type solid)
			)
			(layer "F.Fab")
		)
		(fp_line
			(start 0.998 -0.5)
			(end 0.998 0.498)
			(stroke
				(width 0.15)
				(type solid)
			)
			(layer "F.Fab")
		)
		(fp_line
			(start 0.998 0.498)
			(end -1 0.498)
			(stroke
				(width 0.15)
				(type solid)
			)
			(layer "F.Fab")
		)
		(pad "1" smd roundrect
			(at -0.8875 0.45)
			(size 0.525 0.5)
			(layers "F.Cu" "F.Mask" "F.Paste")
			(roundrect_rratio 0.25)
			(net 143 "/SODIMM/LPDDR5_IN_B.DQ8")
			(pinfunction "R1.1")
			(pintype "passive")
		)
		(pad "2" smd roundrect
			(at -0.25 0.45)
			(size 0.25 0.5)
			(layers "F.Cu" "F.Mask" "F.Paste")
			(roundrect_rratio 0.25)
			(net 141 "/SODIMM/LPDDR5_IN_B.DQ10")
			(pinfunction "R2.1")
			(pintype "passive")
		)
		(pad "3" smd roundrect
			(at 0.25 0.45)
			(size 0.25 0.5)
			(layers "F.Cu" "F.Mask" "F.Paste")
			(roundrect_rratio 0.25)
			(net 142 "/SODIMM/LPDDR5_IN_B.DQ9")
			(pinfunction "R3.1")
			(pintype "passive")
		)
		(pad "4" smd roundrect
			(at 0.8875 0.45)
			(size 0.525 0.5)
			(layers "F.Cu" "F.Mask" "F.Paste")
			(roundrect_rratio 0.25)
			(net 140 "/SODIMM/LPDDR5_IN_B.DQ11")
			(pinfunction "R4.1")
			(pintype "passive")
		)
		(pad "5" smd roundrect
			(at 0.8875 -0.45)
			(size 0.525 0.5)
			(layers "F.Cu" "F.Mask" "F.Paste")
			(roundrect_rratio 0.25)
			(net 209 "/LPDDR5/LPDDR5_B.DQ11")
			(pinfunction "R4.2")
			(pintype "passive")
		)
		(pad "6" smd roundrect
			(at 0.25 -0.45)
			(size 0.25 0.5)
			(layers "F.Cu" "F.Mask" "F.Paste")
			(roundrect_rratio 0.25)
			(net 207 "/LPDDR5/LPDDR5_B.DQ9")
			(pinfunction "R3.2")
			(pintype "passive")
		)
		(pad "7" smd roundrect
			(at -0.25 -0.45)
			(size 0.25 0.5)
			(layers "F.Cu" "F.Mask" "F.Paste")
			(roundrect_rratio 0.25)
			(net 208 "/LPDDR5/LPDDR5_B.DQ10")
			(pinfunction "R2.2")
			(pintype "passive")
		)
		(pad "8" smd roundrect
			(at -0.8875 -0.45)
			(size 0.525 0.5)
			(layers "F.Cu" "F.Mask" "F.Paste")
			(roundrect_rratio 0.25)
			(net 206 "/LPDDR5/LPDDR5_B.DQ8")
			(pinfunction "R1.2")
			(pintype "passive")
		)
	)
	(footprint "antmicro-footprints:TP_SMD_1mm"
		(layer "F.Cu")
		(at 120.75 65.4 90)
		(property "Reference" "TP3"
			(at 0.6 0.35 90)
			(unlocked yes)
			(layer "F.SilkS")
			(effects
				(font
					(size 0.7 0.7)
					(thickness 0.15)
				)
				(justify left bottom)
			)
		)
		(property "Value" "TP_1mm_SMD"
			(at 0 1.4 90)
			(layer "F.Fab")
			(effects
				(font
					(size 0.7 0.7)
					(thickness 0.15)
				)
				(justify left bottom)
			)
		)
		(property "Author" "Antmicro"
			(at 186.15 -55.35 0)
			(layer "F.Fab")
			(hide yes)
			(effects
				(font
					(size 1 1)
					(thickness 0.15)
				)
			)
		)
		(property "License" "Apache-2.0"
			(at 186.15 -55.35 0)
			(layer "F.Fab")
			(hide yes)
			(effects
				(font
					(size 1 1)
					(thickness 0.15)
				)
			)
		)
		(property "MPN" ""
			(at 186.15 -55.35 0)
			(layer "F.Fab")
			(hide yes)
			(effects
				(font
					(size 1 1)
					(thickness 0.15)
				)
			)
		)
		(property "Manufacturer" ""
			(at 186.15 -55.35 0)
			(layer "F.Fab")
			(hide yes)
			(effects
				(font
					(size 1 1)
					(thickness 0.15)
				)
			)
		)
		(sheetname "Power supply")
		(sheetfile "power_supply.kicad_sch")
		(attr exclude_from_pos_files)
		(pad "1" smd circle
			(at 0 0 90)
			(size 1 1)
			(layers "F.Cu" "F.Mask")
			(net 39 "/Power supply/I2C.SCL")
			(pinfunction "1")
			(pintype "passive")
		)
	)
	(footprint "antmicro-footprints:C_0603_1608Metric"
		(layer "F.Cu")
		(at 108.025 61.075)
		(descr "Capacitor SMD 0603")
		(tags "capacitor 0603")
		(property "Reference" "C15"
			(at 1.025 1.35 0)
			(unlocked yes)
			(layer "F.SilkS")
			(effects
				(font
					(size 0.7 0.7)
					(thickness 0.15)
				)
				(justify left bottom)
			)
		)
		(property "Value" "C_22u_0603"
			(at -1.42757 1.770288 0)
			(layer "F.Fab")
			(effects
				(font
					(size 0.7 0.7)
					(thickness 0.15)
				)
				(justify left bottom)
			)
		)
		(property "Author" "Antmicro"
			(at 0 0 0)
			(layer "F.Fab")
			(hide yes)
			(effects
				(font
					(size 1 1)
					(thickness 0.15)
				)
			)
		)
		(property "Dielectric" ""
			(at 0 0 0)
			(layer "F.Fab")
			(hide yes)
			(effects
				(font
					(size 1 1)
					(thickness 0.15)
				)
			)
		)
		(property "License" "Apache-2.0"
			(at 0 0 0)
			(layer "F.Fab")
			(hide yes)
			(effects
				(font
					(size 1 1)
					(thickness 0.15)
				)
			)
		)
		(property "MPN" "GRM188R60J226MEA0D"
			(at 0 0 0)
			(layer "F.Fab")
			(hide yes)
			(effects
				(font
					(size 1 1)
					(thickness 0.15)
				)
			)
		)
		(property "Manufacturer" "Murata"
			(at 0 0 0)
			(layer "F.Fab")
			(hide yes)
			(effects
				(font
					(size 1 1)
					(thickness 0.15)
				)
			)
		)
		(property "Val" "22u"
			(at 0 0 0)
			(layer "F.Fab")
			(hide yes)
			(effects
				(font
					(size 1 1)
					(thickness 0.15)
				)
			)
		)
		(property "Voltage" ""
			(at 0 0 0)
			(layer "F.Fab")
			(hide yes)
			(effects
				(font
					(size 1 1)
					(thickness 0.15)
				)
			)
		)
		(sheetname "Power supply")
		(sheetfile "power_supply.kicad_sch")
		(attr smd)
		(fp_line
			(start -0.3 -0.3)
			(end 0.3 -0.3)
			(stroke
				(width 0.15)
				(type solid)
			)
			(layer "F.SilkS")
		)
		(fp_line
			(start -0.3 0.3)
			(end 0.3 0.3)
			(stroke
				(width 0.15)
				(type solid)
			)
			(layer "F.SilkS")
		)
		(fp_rect
			(start -1.24 -0.7)
			(end 1.24 0.7)
			(stroke
				(width 0.05)
				(type solid)
			)
			(fill no)
			(layer "F.CrtYd")
		)
		(fp_rect
			(start -0.8 -0.4)
			(end 0.8 0.4)
			(stroke
				(width 0.15)
				(type solid)
			)
			(fill no)
			(layer "F.Fab")
		)
		(pad "1" smd roundrect
			(at -0.7 0)
			(size 0.6 0.8)
			(layers "F.Cu" "F.Mask" "F.Paste")
			(roundrect_rratio 0.2)
			(net 14 "GND")
			(pintype "passive")
		)
		(pad "2" smd roundrect
			(at 0.7 0)
			(size 0.6 0.8)
			(layers "F.Cu" "F.Mask" "F.Paste")
			(roundrect_rratio 0.2)
			(net 8 "/Power supply/VOUT2")
			(pintype "passive")
		)
	)
)
